# S9S_MB_2U (Grand Teton) — schematic netlist excerpt (pin names and nets, part order shuffled) for the footprints in the layout excerpt that follows; sources: Cadence DE-HDL packaged netlist, KiCad conversion of 03242023_DA0F0TMBIJ0_F0T_Motherboard_J_brd_V01_OCP.brd

R3942  Q_RES  0 5% CHIP  pkg 0402LF  page 250 : A = P12V_E1S_0_ISENSE_MPS_TIC ; B = P12V_E1S_0_ISENSE_TIC
R4533  Q_RES  2K 1% EMPTY  pkg 0402LF  page 219 : A = PWRGD_DRAMPWRGD_CPU1_GH_R_LVC1 ; B = GND

(kicad_pcb
	(version 20260206)
	(generator "pcbnew")
	(generator_version "10.0")
	(general
		(thickness 1.6)
		(legacy_teardrops no)
	)
	(paper "A4")
	(title_block
		(title "03242023_DA0F0TMBIJ0_F0T_Motherboard_J_brd_V01_OCP.brd")
		(comment 1 "Grand Teton / footprints 4452-4453 of 6105")
	)
	(layers
		(0 "F.Cu" signal "TOP")
		(4 "In1.Cu" signal "GND")
		(6 "In2.Cu" signal "IN1")
		(8 "In3.Cu" signal "GND1")
		(10 "In4.Cu" signal "IN2")
		(12 "In5.Cu" signal "GND2")
		(14 "In6.Cu" signal "IN3")
		(16 "In7.Cu" signal "GND3")
		(18 "In8.Cu" signal "VCC")
		(20 "In9.Cu" signal "VCC1")
		(22 "In10.Cu" signal "GND4")
		(24 "In11.Cu" signal "IN4")
		(26 "In12.Cu" signal "GND5")
		(28 "In13.Cu" signal "IN5")
		(30 "In14.Cu" signal "GND6")
		(32 "In15.Cu" signal "IN6")
		(34 "In16.Cu" signal "GND7")
		(2 "B.Cu" signal "BOTTOM")
		(9 "F.Adhes" user "F.Adhesive")
		(11 "B.Adhes" user "B.Adhesive")
		(13 "F.Paste" user "Package Geometry/Pastemask Top")
		(15 "B.Paste" user "Package Geometry/Pastemask Bottom")
		(5 "F.SilkS" user "Ref Des/Silkscreen Top")
		(7 "B.SilkS" user "Ref Des/Silkscreen Bottom")
		(1 "F.Mask" user "Board Geometry/Soldermask Top")
		(3 "B.Mask" user "Board Geometry/Soldermask Bottom")
		(17 "Dwgs.User" user "User.Drawings")
		(19 "Cmts.User" user "User.Comments")
		(21 "Eco1.User" user "User.Eco1")
		(23 "Eco2.User" user "User.Eco2")
		(25 "Edge.Cuts" user "Board Geometry/Outline")
		(27 "Margin" user)
		(31 "F.CrtYd" user "Package Geometry/Place Bound Top")
		(29 "B.CrtYd" user "Package Geometry/Place Bound Bottom")
		(35 "F.Fab" user "Ref Des/Assembly Top")
		(33 "B.Fab" user "Ref Des/Assembly Bottom")
	)
	(footprint ""
		(layer "B.Cu")
		(at 257.35407 -55.436262)
		(property "Reference" "R3942"
			(at 0 0 0)
			(layer "B.SilkS")
			(hide yes)
			(effects
				(font
					(size 1.27 1.27)
				)
				(justify mirror)
			)
		)
		(property "Value" ""
			(at 0 0 0)
			(layer "B.Fab")
			(effects
				(font
					(size 1.27 1.27)
				)
				(justify mirror)
			)
		)
		(duplicate_pad_numbers_are_jumpers no)
		(fp_line
			(start -0.7874 -0.4064)
			(end -0.7874 0.4064)
			(stroke
				(width 0.1524)
				(type default)
			)
			(layer "B.SilkS")
		)
		(fp_line
			(start -0.7874 0.4064)
			(end 0.7874 0.4064)
			(stroke
				(width 0.1524)
				(type default)
			)
			(layer "B.SilkS")
		)
		(fp_line
			(start 0.7874 -0.4064)
			(end -0.7874 -0.4064)
			(stroke
				(width 0.1524)
				(type default)
			)
			(layer "B.SilkS")
		)
		(fp_line
			(start 0.7874 0.4064)
			(end 0.7874 -0.4064)
			(stroke
				(width 0.1524)
				(type default)
			)
			(layer "B.SilkS")
		)
		(fp_line
			(start -0.67945 -0.3048)
			(end -0.67945 0.3048)
			(stroke
				(width 0.1)
				(type default)
			)
			(layer "B.Fab")
		)
		(fp_line
			(start -0.67945 0.3048)
			(end -0.120396 0.3048)
			(stroke
				(width 0.1)
				(type default)
			)
			(layer "B.Fab")
		)
		(fp_line
			(start -0.12065 -0.3048)
			(end -0.67945 -0.3048)
			(stroke
				(width 0.1)
				(type default)
			)
			(layer "B.Fab")
		)
		(fp_line
			(start -0.12065 -0.2794)
			(end -0.12065 -0.3048)
			(stroke
				(width 0.1)
				(type default)
			)
			(layer "B.Fab")
		)
		(fp_line
			(start -0.120396 0.2794)
			(end 0.12065 0.2794)
			(stroke
				(width 0.1)
				(type default)
			)
			(layer "B.Fab")
		)
		(fp_line
			(start -0.120396 0.3048)
			(end -0.120396 0.2794)
			(stroke
				(width 0.1)
				(type default)
			)
			(layer "B.Fab")
		)
		(fp_line
			(start 0.12065 -0.305054)
			(end 0.12065 -0.2794)
			(stroke
				(width 0.1)
				(type default)
			)
			(layer "B.Fab")
		)
		(fp_line
			(start 0.12065 -0.2794)
			(end -0.12065 -0.2794)
			(stroke
				(width 0.1)
				(type default)
			)
			(layer "B.Fab")
		)
		(fp_line
			(start 0.12065 0.2794)
			(end 0.12065 0.3048)
			(stroke
				(width 0.1)
				(type default)
			)
			(layer "B.Fab")
		)
		(fp_line
			(start 0.12065 0.3048)
			(end 0.67945 0.3048)
			(stroke
				(width 0.1)
				(type default)
			)
			(layer "B.Fab")
		)
		(fp_line
			(start 0.67945 -0.305054)
			(end 0.12065 -0.305054)
			(stroke
				(width 0.1)
				(type default)
			)
			(layer "B.Fab")
		)
		(fp_line
			(start 0.67945 0.3048)
			(end 0.67945 -0.305054)
			(stroke
				(width 0.1)
				(type default)
			)
			(layer "B.Fab")
		)
		(pad "1" smd rect
			(at 0.40005 0)
			(size 0.4572 0.508)
			(layers "B.Cu" "B.Mask" "B.Paste")
			(net "P12V_E1S_0_ISENSE_MPS_TIC")
		)
		(pad "2" smd rect
			(at -0.40005 0)
			(size 0.4572 0.508)
			(layers "B.Cu" "B.Mask" "B.Paste")
			(net "P12V_E1S_0_ISENSE_TIC")
		)
	)
	(footprint ""
		(layer "B.Cu")
		(at 205.446122 -108.490766 90)
		(property "Reference" "R4533"
			(at 0 0 90)
			(layer "B.SilkS")
			(hide yes)
			(effects
				(font
					(size 1.27 1.27)
				)
				(justify mirror)
			)
		)
		(property "Value" ""
			(at 0 0 90)
			(layer "B.Fab")
			(effects
				(font
					(size 1.27 1.27)
				)
				(justify mirror)
			)
		)
		(duplicate_pad_numbers_are_jumpers no)
		(fp_line
			(start 0.7874 -0.4064)
			(end -0.7874 -0.4064)
			(stroke
				(width 0.1524)
				(type default)
			)
			(layer "B.SilkS")
		)
		(fp_line
			(start -0.7874 -0.4064)
			(end -0.7874 0.4064)
			(stroke
				(width 0.1524)
				(type default)
			)
			(layer "B.SilkS")
		)
		(fp_line
			(start 0.7874 0.4064)
			(end 0.7874 -0.4064)
			(stroke
				(width 0.1524)
				(type default)
			)
			(layer "B.SilkS")
		)
		(fp_line
			(start -0.7874 0.4064)
			(end 0.7874 0.4064)
			(stroke
				(width 0.1524)
				(type default)
			)
			(layer "B.SilkS")
		)
		(fp_line
			(start 0.67945 -0.305054)
			(end 0.12065 -0.305054)
			(stroke
				(width 0.1)
				(type default)
			)
			(layer "B.Fab")
		)
		(fp_line
			(start 0.12065 -0.305054)
			(end 0.12065 -0.2794)
			(stroke
				(width 0.1)
				(type default)
			)
			(layer "B.Fab")
		)
		(fp_line
			(start -0.12065 -0.3048)
			(end -0.67945 -0.3048)
			(stroke
				(width 0.1)
				(type default)
			)
			(layer "B.Fab")
		)
		(fp_line
			(start -0.67945 -0.3048)
			(end -0.67945 0.3048)
			(stroke
				(width 0.1)
				(type default)
			)
			(layer "B.Fab")
		)
		(fp_line
			(start 0.12065 -0.2794)
			(end -0.12065 -0.2794)
			(stroke
				(width 0.1)
				(type default)
			)
			(layer "B.Fab")
		)
		(fp_line
			(start -0.12065 -0.2794)
			(end -0.12065 -0.3048)
			(stroke
				(width 0.1)
				(type default)
			)
			(layer "B.Fab")
		)
		(fp_line
			(start 0.12065 0.2794)
			(end 0.12065 0.3048)
			(stroke
				(width 0.1)
				(type default)
			)
			(layer "B.Fab")
		)
		(fp_line
			(start -0.120396 0.2794)
			(end 0.12065 0.2794)
			(stroke
				(width 0.1)
				(type default)
			)
			(layer "B.Fab")
		)
		(fp_line
			(start 0.67945 0.3048)
			(end 0.67945 -0.305054)
			(stroke
				(width 0.1)
				(type default)
			)
			(layer "B.Fab")
		)
		(fp_line
			(start 0.12065 0.3048)
			(end 0.67945 0.3048)
			(stroke
				(width 0.1)
				(type default)
			)
			(layer "B.Fab")
		)
		(fp_line
			(start -0.120396 0.3048)
			(end -0.120396 0.2794)
			(stroke
				(width 0.1)
				(type default)
			)
			(layer "B.Fab")
		)
		(fp_line
			(start -0.67945 0.3048)
			(end -0.120396 0.3048)
			(stroke
				(width 0.1)
				(type default)
			)
			(layer "B.Fab")
		)
		(pad "1" smd circle
			(at 0.40005 0 270)
			(size 0 0)
			(layers "B.Cu" "B.Mask" "B.Paste")
			(net "PWRGD_DRAMPWRGD_CPU1_GH_R_LVC1")
		)
		(pad "2" smd circle
			(at -0.40005 0 270)
			(size 0 0)
			(layers "B.Cu" "B.Mask" "B.Paste")
			(net "GND")
		)
	)
)
